(kicad_pcb
	(version 20260206)
	(generator "pcbnew")
	(generator_version "10.0")
	(general
		(thickness 1.6)
		(legacy_teardrops no)
	)
	(paper "A4")
	(title_block
		(title "fcb — 12433-1M.1206WZS1330.brd")
		(comment 1 "Open Vault / Knox (Wiwynn) / footprints 365-371 of 495")
	)
	(layers
		(0 "F.Cu" signal "TOP")
		(4 "In1.Cu" signal "L2GND")
		(6 "In2.Cu" signal "L3VCC")
		(2 "B.Cu" signal "BOTTOM")
		(9 "F.Adhes" user "F.Adhesive")
		(11 "B.Adhes" user "B.Adhesive")
		(13 "F.Paste" user "Package Geometry/Pastemask Top")
		(15 "B.Paste" user "Package Geometry/Pastemask Bottom")
		(5 "F.SilkS" user "Ref Des/Silkscreen Top")
		(7 "B.SilkS" user "Ref Des/Silkscreen Bottom")
		(1 "F.Mask" user "Board Geometry/Soldermask Top")
		(3 "B.Mask" user "Board Geometry/Soldermask Bottom")
		(17 "Dwgs.User" user "User.Drawings")
		(19 "Cmts.User" user "User.Comments")
		(21 "Eco1.User" user "User.Eco1")
		(23 "Eco2.User" user "User.Eco2")
		(25 "Edge.Cuts" user "Board Geometry/Outline")
		(27 "Margin" user)
		(31 "F.CrtYd" user "Package Geometry/Place Bound Top")
		(29 "B.CrtYd" user "Package Geometry/Place Bound Bottom")
		(35 "F.Fab" user "Ref Des/Assembly Top")
		(33 "B.Fab" user "Ref Des/Assembly Bottom")
	)
	(footprint ""
		(layer "F.Cu")
		(at 19.9136 -149.6822)
		(property "Reference" "R76"
			(at 0 0 0)
			(layer "F.SilkS")
			(hide yes)
			(effects
				(font
					(size 1.27 1.27)
				)
			)
		)
		(property "Value" "10KR2F-2-GP"
			(at 0.064008 -3.993896 0)
			(unlocked yes)
			(layer "F.Fab")
			(hide yes)
			(effects
				(font
					(size 1.016 1.016)
					(thickness 0.1524)
				)
			)
		)
		(property "Device Type" "R402H16"
			(at 0.064008 -5.517896 0)
			(unlocked yes)
			(layer "F.Fab")
			(hide yes)
			(effects
				(font
					(size 1.016 1.016)
					(thickness 0.1524)
				)
			)
		)
		(duplicate_pad_numbers_are_jumpers no)
		(fp_line
			(start -0.508 -0.9398)
			(end -0.508 0.9398)
			(stroke
				(width 0.1524)
				(type default)
			)
			(layer "F.SilkS")
		)
		(fp_line
			(start 0.508 -0.9398)
			(end -0.508 -0.9398)
			(stroke
				(width 0.1524)
				(type default)
			)
			(layer "F.SilkS")
		)
		(fp_rect
			(start -0.508 0.9398)
			(end 0.508 -0.9398)
			(stroke
				(width 0)
				(type default)
			)
			(fill no)
			(layer "F.CrtYd")
		)
		(fp_rect
			(start -0.508 0.9398)
			(end 0.508 -0.9398)
			(stroke
				(width 0)
				(type default)
			)
			(fill no)
			(layer "F.Fab")
		)
		(pad "1" smd custom
			(at 0 -0.4445)
			(size 0.1397 0.1397)
			(layers "F.Cu" "F.Mask" "F.Paste")
			(net "FANIN_9")
			(options
				(clearance outline)
				(anchor circle)
			)
			(primitives
				(gr_poly
					(pts
						(arc
							(start -0.1778 -0.2794)
							(mid -0.249642 -0.249642)
							(end -0.2794 -0.1778)
						)
						(arc
							(start -0.2794 0.1778)
							(mid -0.249642 0.249642)
							(end -0.1778 0.2794)
						)
						(arc
							(start 0.1778 0.2794)
							(mid 0.249642 0.249642)
							(end 0.2794 0.1778)
						)
						(arc
							(start 0.2794 -0.1778)
							(mid 0.249642 -0.249642)
							(end 0.1778 -0.2794)
						)
					)
					(width 0)
					(fill yes)
				)
			)
		)
		(pad "2" smd custom
			(at 0 0.4445)
			(size 0.1397 0.1397)
			(layers "F.Cu" "F.Mask" "F.Paste")
			(net "GND")
			(options
				(clearance outline)
				(anchor circle)
			)
			(primitives
				(gr_poly
					(pts
						(arc
							(start -0.1778 -0.2794)
							(mid -0.249642 -0.249642)
							(end -0.2794 -0.1778)
						)
						(arc
							(start -0.2794 0.1778)
							(mid -0.249642 0.249642)
							(end -0.1778 0.2794)
						)
						(arc
							(start 0.1778 0.2794)
							(mid 0.249642 0.249642)
							(end 0.2794 0.1778)
						)
						(arc
							(start 0.2794 -0.1778)
							(mid 0.249642 -0.249642)
							(end 0.1778 -0.2794)
						)
					)
					(width 0)
					(fill yes)
				)
			)
		)
	)
	(footprint ""
		(layer "F.Cu")
		(at 31.012638 -289.229292 -90)
		(property "Reference" "F5"
			(at 0 0 270)
			(layer "F.SilkS")
			(hide yes)
			(effects
				(font
					(size 1.27 1.27)
				)
			)
		)
		(property "Value" "FUSE-3A15V-GP"
			(at 0.2286 -10.5918 270)
			(unlocked yes)
			(layer "F.Fab")
			(hide yes)
			(effects
				(font
					(size 1.016 1.016)
					(thickness 0.1524)
				)
			)
		)
		(property "Device Type" "FUSE-7452-UH50"
			(at 0.2286 -12.4968 270)
			(unlocked yes)
			(layer "F.Fab")
			(hide yes)
			(effects
				(font
					(size 1.016 1.016)
					(thickness 0.1524)
				)
			)
		)
		(duplicate_pad_numbers_are_jumpers no)
		(fp_line
			(start -4.9276 2.921)
			(end -4.9276 -2.921)
			(stroke
				(width 0.1524)
				(type default)
			)
			(layer "F.SilkS")
		)
		(fp_line
			(start 4.9276 2.921)
			(end -4.9276 2.921)
			(stroke
				(width 0.1524)
				(type default)
			)
			(layer "F.SilkS")
		)
		(fp_line
			(start -4.9276 -2.921)
			(end 4.9276 -2.921)
			(stroke
				(width 0.1524)
				(type default)
			)
			(layer "F.SilkS")
		)
		(fp_line
			(start 4.9276 -2.921)
			(end 4.9276 2.921)
			(stroke
				(width 0.1524)
				(type default)
			)
			(layer "F.SilkS")
		)
		(fp_poly
			(pts
				(xy -5.08 3.0988) (xy 5.08 3.0988) (xy 5.08 -3.0988) (xy -5.08 -3.0988)
			)
			(stroke
				(width 0)
				(type default)
			)
			(fill no)
			(layer "F.CrtYd")
		)
		(fp_poly
			(pts
				(xy -5.08 -3.0988) (xy 5.08 -3.0988) (xy 5.08 3.0988) (xy -5.08 3.0988)
			)
			(stroke
				(width 0)
				(type default)
			)
			(fill no)
			(layer "F.Fab")
		)
		(pad "1" smd rect
			(at -3.4036 0 270)
			(size 2.2098 5.2832)
			(layers "F.Cu" "F.Mask" "F.Paste")
			(net "P12V_FAN2")
		)
		(pad "2" smd rect
			(at 3.4036 0 270)
			(size 2.2098 5.2832)
			(layers "F.Cu" "F.Mask" "F.Paste")
			(net "P12V")
		)
	)
	(footprint ""
		(layer "F.Cu")
		(at 40.005 -371.475 -90)
		(property "Reference" "C255"
			(at 0 0 270)
			(layer "F.SilkS")
			(hide yes)
			(effects
				(font
					(size 1.27 1.27)
				)
			)
		)
		(property "Value" "SCD1U25V3KX-LL-GP"
			(at 0 -2.8194 270)
			(unlocked yes)
			(layer "F.Fab")
			(hide yes)
			(effects
				(font
					(size 1.016 1.016)
					(thickness 0.1524)
				)
			)
		)
		(property "Device Type" "C603H36"
			(at 0 -4.3434 270)
			(unlocked yes)
			(layer "F.Fab")
			(hide yes)
			(effects
				(font
					(size 1.016 1.016)
					(thickness 0.1524)
				)
			)
		)
		(duplicate_pad_numbers_are_jumpers no)
		(fp_line
			(start 0.508 0)
			(end -0.508 0)
			(stroke
				(width 0.2032)
				(type default)
			)
			(layer "F.SilkS")
		)
		(fp_rect
			(start -0.5842 1.3335)
			(end 0.5842 -1.3335)
			(stroke
				(width 0)
				(type default)
			)
			(fill no)
			(layer "F.CrtYd")
		)
		(fp_rect
			(start -0.5842 1.3335)
			(end 0.5842 -1.3335)
			(stroke
				(width 0)
				(type default)
			)
			(fill no)
			(layer "F.Fab")
		)
		(pad "1" smd custom
			(at 0 -0.762 270)
			(size 0.2159 0.2159)
			(layers "F.Cu" "F.Mask" "F.Paste")
			(net "ADM1276_LATCH_B")
			(options
				(clearance outline)
				(anchor circle)
			)
			(primitives
				(gr_poly
					(pts
						(arc
							(start -0.3302 -0.4318)
							(mid -0.402042 -0.402042)
							(end -0.4318 -0.3302)
						)
						(arc
							(start -0.4318 0.3302)
							(mid -0.402042 0.402042)
							(end -0.3302 0.4318)
						)
						(arc
							(start 0.3302 0.4318)
							(mid 0.402042 0.402042)
							(end 0.4318 0.3302)
						)
						(arc
							(start 0.4318 -0.3302)
							(mid 0.402042 -0.402042)
							(end 0.3302 -0.4318)
						)
					)
					(width 0)
					(fill yes)
				)
			)
		)
		(pad "2" smd custom
			(at 0 0.762 270)
			(size 0.2159 0.2159)
			(layers "F.Cu" "F.Mask" "F.Paste")
			(net "GND")
			(options
				(clearance outline)
				(anchor circle)
			)
			(primitives
				(gr_poly
					(pts
						(arc
							(start -0.3302 -0.4318)
							(mid -0.402042 -0.402042)
							(end -0.4318 -0.3302)
						)
						(arc
							(start -0.4318 0.3302)
							(mid -0.402042 0.402042)
							(end -0.3302 0.4318)
						)
						(arc
							(start 0.3302 0.4318)
							(mid 0.402042 0.402042)
							(end 0.4318 0.3302)
						)
						(arc
							(start 0.4318 -0.3302)
							(mid 0.402042 -0.402042)
							(end 0.3302 -0.4318)
						)
					)
					(width 0)
					(fill yes)
				)
			)
		)
	)
	(footprint ""
		(layer "F.Cu")
		(at 17.9832 -248.5644 180)
		(property "Reference" "PR52"
			(at 0 0 180)
			(layer "F.SilkS")
			(hide yes)
			(effects
				(font
					(size 1.27 1.27)
				)
			)
		)
		(property "Value" "47KR3F-GP"
			(at -0.0254 -2.5146 180)
			(unlocked yes)
			(layer "F.Fab")
			(hide yes)
			(effects
				(font
					(size 1.016 1.016)
					(thickness 0.1524)
				)
			)
		)
		(property "Device Type" "R603H22"
			(at -0.0254 -4.0386 180)
			(unlocked yes)
			(layer "F.Fab")
			(hide yes)
			(effects
				(font
					(size 1.016 1.016)
					(thickness 0.1524)
				)
			)
		)
		(duplicate_pad_numbers_are_jumpers no)
		(fp_line
			(start 0.2032 0)
			(end 0.4826 0)
			(stroke
				(width 0.2032)
				(type default)
			)
			(layer "F.SilkS")
		)
		(fp_line
			(start -0.4826 0)
			(end -0.2032 0)
			(stroke
				(width 0.2032)
				(type default)
			)
			(layer "F.SilkS")
		)
		(fp_rect
			(start -0.5842 1.3335)
			(end 0.5842 -1.3335)
			(stroke
				(width 0)
				(type default)
			)
			(fill no)
			(layer "F.CrtYd")
		)
		(fp_rect
			(start -0.5842 1.3335)
			(end 0.5842 -1.3335)
			(stroke
				(width 0)
				(type default)
			)
			(fill no)
			(layer "F.Fab")
		)
		(pad "1" smd custom
			(at 0 -0.762 180)
			(size 0.2159 0.2159)
			(layers "F.Cu" "F.Mask" "F.Paste")
			(net "P3V3_IN")
			(options
				(clearance outline)
				(anchor circle)
			)
			(primitives
				(gr_poly
					(pts
						(arc
							(start -0.3302 -0.4318)
							(mid -0.402042 -0.402042)
							(end -0.4318 -0.3302)
						)
						(arc
							(start -0.4318 0.3302)
							(mid -0.402042 0.402042)
							(end -0.3302 0.4318)
						)
						(arc
							(start 0.3302 0.4318)
							(mid 0.402042 0.402042)
							(end 0.4318 0.3302)
						)
						(arc
							(start 0.4318 -0.3302)
							(mid 0.402042 -0.402042)
							(end 0.3302 -0.4318)
						)
					)
					(width 0)
					(fill yes)
				)
			)
		)
		(pad "2" smd custom
			(at 0 0.762 180)
			(size 0.2159 0.2159)
			(layers "F.Cu" "F.Mask" "F.Paste")
			(net "P3V3_EN")
			(options
				(clearance outline)
				(anchor circle)
			)
			(primitives
				(gr_poly
					(pts
						(arc
							(start -0.3302 -0.4318)
							(mid -0.402042 -0.402042)
							(end -0.4318 -0.3302)
						)
						(arc
							(start -0.4318 0.3302)
							(mid -0.402042 0.402042)
							(end -0.3302 0.4318)
						)
						(arc
							(start 0.3302 0.4318)
							(mid 0.402042 0.402042)
							(end 0.4318 0.3302)
						)
						(arc
							(start 0.4318 -0.3302)
							(mid 0.402042 -0.402042)
							(end 0.3302 -0.4318)
						)
					)
					(width 0)
					(fill yes)
				)
			)
		)
	)
	(footprint ""
		(layer "F.Cu")
		(at 44.831 -111.633)
		(property "Reference" "PQ12"
			(at 0 0 0)
			(layer "F.SilkS")
			(hide yes)
			(effects
				(font
					(size 1.27 1.27)
				)
			)
		)
		(property "Value" "PH0925CL-GP"
			(at -4.2799 -0.4572 0)
			(unlocked yes)
			(layer "F.Fab")
			(hide yes)
			(effects
				(font
					(size 1.016 1.016)
					(thickness 0.1524)
				)
			)
		)
		(property "Device Type" "LFPAK-5PH48-U"
			(at -4.2799 -1.9812 0)
			(unlocked yes)
			(layer "F.Fab")
			(hide yes)
			(effects
				(font
					(size 1.016 1.016)
					(thickness 0.1524)
				)
			)
		)
		(duplicate_pad_numbers_are_jumpers no)
		(fp_line
			(start -2.7559 -6.5532)
			(end -2.7559 1.0668)
			(stroke
				(width 0.1524)
				(type default)
			)
			(layer "F.SilkS")
		)
		(fp_line
			(start -2.7559 1.0668)
			(end 2.7559 1.0668)
			(stroke
				(width 0.1524)
				(type default)
			)
			(layer "F.SilkS")
		)
		(fp_line
			(start -1.7272 1.1684)
			(end -2.1082 1.1684)
			(stroke
				(width 0.3302)
				(type default)
			)
			(layer "F.SilkS")
		)
		(fp_line
			(start 2.7559 -6.5532)
			(end -2.7559 -6.5532)
			(stroke
				(width 0.1524)
				(type default)
			)
			(layer "F.SilkS")
		)
		(fp_line
			(start 2.7559 1.0668)
			(end 2.7559 -6.5532)
			(stroke
				(width 0.1524)
				(type default)
			)
			(layer "F.SilkS")
		)
		(fp_poly
			(pts
				(xy -2.3368 1.5748) (xy -1.905 1.143) (xy -1.4732 1.5748)
			)
			(stroke
				(width 0)
				(type default)
			)
			(fill yes)
			(layer "F.SilkS")
		)
		(fp_poly
			(pts
				(xy -2.5019 -4.02971) (xy -0.3302 -4.02971) (xy -0.3302 -6.30301) (xy -2.5019 -6.30301)
			)
			(stroke
				(width 0)
				(type default)
			)
			(fill yes)
			(layer "F.Paste")
		)
		(fp_poly
			(pts
				(xy -2.5019 -1.09601) (xy -0.3302 -1.09601) (xy -0.3302 -3.36931) (xy -2.5019 -3.36931)
			)
			(stroke
				(width 0)
				(type default)
			)
			(fill yes)
			(layer "F.Paste")
		)
		(fp_poly
			(pts
				(xy 0.3302 -4.02971) (xy 2.5019 -4.02971) (xy 2.5019 -6.30301) (xy 0.3302 -6.30301)
			)
			(stroke
				(width 0)
				(type default)
			)
			(fill yes)
			(layer "F.Paste")
		)
		(fp_poly
			(pts
				(xy 0.3302 -1.09601) (xy 2.5019 -1.09601) (xy 2.5019 -3.36931) (xy 0.3302 -3.36931)
			)
			(stroke
				(width 0)
				(type default)
			)
			(fill yes)
			(layer "F.Paste")
		)
		(fp_rect
			(start -2.4511 0.3048)
			(end 2.4511 -5.6896)
			(stroke
				(width 0)
				(type default)
			)
			(fill no)
			(layer "F.CrtYd")
		)
		(fp_poly
			(pts
				(xy -3.0099 1.3208) (xy -3.0099 -6.8072) (xy 3.0099 -6.8072) (xy 3.0099 -1.016) (xy 2.4511 -1.016)
				(xy 2.4511 -5.6896) (xy -2.4511 -5.6896) (xy -2.4511 0.3048) (xy 2.4511 0.3048) (xy 2.4511 -1.0033)
				(xy 3.0099 -1.0033) (xy 3.0099 1.3208)
			)
			(stroke
				(width 0)
				(type default)
			)
			(fill no)
			(layer "F.CrtYd")
		)
		(fp_rect
			(start -3.0099 1.3208)
			(end 3.0099 -6.8072)
			(stroke
				(width 0)
				(type default)
			)
			(fill no)
			(layer "F.Fab")
		)
		(pad "1" smd rect
			(at -1.905 0)
			(size 0.762 1.6256)
			(layers "F.Cu" "F.Mask" "F.Paste")
			(net "P12VL")
		)
		(pad "2" smd rect
			(at -0.635 0)
			(size 0.762 1.6256)
			(layers "F.Cu" "F.Mask" "F.Paste")
			(net "P12VL")
		)
		(pad "3" smd rect
			(at 0.635 0)
			(size 0.762 1.6256)
			(layers "F.Cu" "F.Mask" "F.Paste")
			(net "P12VL")
		)
		(pad "4" smd rect
			(at 1.905 0)
			(size 0.762 1.6256)
			(layers "F.Cu" "F.Mask" "F.Paste")
			(net "P12VL_2490_GATE_DRV_2")
		)
		(pad "5" smd rect
			(at 0 -3.69951)
			(size 5.0038 5.207)
			(layers "F.Cu" "F.Mask" "F.Paste")
			(net "P12VL_NET")
		)
	)
	(footprint ""
		(layer "F.Cu")
		(at 36.740338 -477.189292 90)
		(property "Reference" "C50"
			(at 0 0 90)
			(layer "F.SilkS")
			(hide yes)
			(effects
				(font
					(size 1.27 1.27)
				)
			)
		)
		(property "Value" "SC1U25V3KX-1-GP"
			(at 0 -2.8194 90)
			(unlocked yes)
			(layer "F.Fab")
			(hide yes)
			(effects
				(font
					(size 1.016 1.016)
					(thickness 0.1524)
				)
			)
		)
		(property "Device Type" "C603H36"
			(at 0 -4.3434 90)
			(unlocked yes)
			(layer "F.Fab")
			(hide yes)
			(effects
				(font
					(size 1.016 1.016)
					(thickness 0.1524)
				)
			)
		)
		(duplicate_pad_numbers_are_jumpers no)
		(fp_line
			(start 0.508 0)
			(end -0.508 0)
			(stroke
				(width 0.2032)
				(type default)
			)
			(layer "F.SilkS")
		)
		(fp_rect
			(start -0.5842 1.3335)
			(end 0.5842 -1.3335)
			(stroke
				(width 0)
				(type default)
			)
			(fill no)
			(layer "F.CrtYd")
		)
		(fp_rect
			(start -0.5842 1.3335)
			(end 0.5842 -1.3335)
			(stroke
				(width 0)
				(type default)
			)
			(fill no)
			(layer "F.Fab")
		)
		(pad "1" smd custom
			(at 0 -0.762 90)
			(size 0.2159 0.2159)
			(layers "F.Cu" "F.Mask" "F.Paste")
			(net "P12V")
			(options
				(clearance outline)
				(anchor circle)
			)
			(primitives
				(gr_poly
					(pts
						(arc
							(start -0.3302 -0.4318)
							(mid -0.402042 -0.402042)
							(end -0.4318 -0.3302)
						)
						(arc
							(start -0.4318 0.3302)
							(mid -0.402042 0.402042)
							(end -0.3302 0.4318)
						)
						(arc
							(start 0.3302 0.4318)
							(mid 0.402042 0.402042)
							(end 0.4318 0.3302)
						)
						(arc
							(start 0.4318 -0.3302)
							(mid 0.402042 -0.402042)
							(end 0.3302 -0.4318)
						)
					)
					(width 0)
					(fill yes)
				)
			)
		)
		(pad "2" smd custom
			(at 0 0.762 90)
			(size 0.2159 0.2159)
			(layers "F.Cu" "F.Mask" "F.Paste")
			(net "GND")
			(options
				(clearance outline)
				(anchor circle)
			)
			(primitives
				(gr_poly
					(pts
						(arc
							(start -0.3302 -0.4318)
							(mid -0.402042 -0.402042)
							(end -0.4318 -0.3302)
						)
						(arc
							(start -0.4318 0.3302)
							(mid -0.402042 0.402042)
							(end -0.3302 0.4318)
						)
						(arc
							(start 0.3302 0.4318)
							(mid 0.402042 0.402042)
							(end 0.4318 0.3302)
						)
						(arc
							(start 0.4318 -0.3302)
							(mid 0.402042 -0.402042)
							(end 0.3302 -0.4318)
						)
					)
					(width 0)
					(fill yes)
				)
			)
		)
	)
	(footprint ""
		(layer "F.Cu")
		(at 28.2448 -210.8454 180)
		(property "Reference" "R137"
			(at 0 0 180)
			(layer "F.SilkS")
			(hide yes)
			(effects
				(font
					(size 1.27 1.27)
				)
			)
		)
		(property "Value" "0R2J-2-GP"
			(at 0.064008 -3.993896 180)
			(unlocked yes)
			(layer "F.Fab")
			(hide yes)
			(effects
				(font
					(size 1.016 1.016)
					(thickness 0.1524)
				)
			)
		)
		(property "Device Type" "R402H16"
			(at 0.064008 -5.517896 180)
			(unlocked yes)
			(layer "F.Fab")
			(hide yes)
			(effects
				(font
					(size 1.016 1.016)
					(thickness 0.1524)
				)
			)
		)
		(duplicate_pad_numbers_are_jumpers no)
		(fp_line
			(start 0.508 -0.9398)
			(end -0.508 -0.9398)
			(stroke
				(width 0.1524)
				(type default)
			)
			(layer "F.SilkS")
		)
		(fp_line
			(start -0.508 -0.9398)
			(end -0.508 0.9398)
			(stroke
				(width 0.1524)
				(type default)
			)
			(layer "F.SilkS")
		)
		(fp_rect
			(start -0.508 0.9398)
			(end 0.508 -0.9398)
			(stroke
				(width 0)
				(type default)
			)
			(fill no)
			(layer "F.CrtYd")
		)
		(fp_rect
			(start -0.508 0.9398)
			(end 0.508 -0.9398)
			(stroke
				(width 0)
				(type default)
			)
			(fill no)
			(layer "F.Fab")
		)
		(pad "1" smd custom
			(at 0 -0.4445 180)
			(size 0.1397 0.1397)
			(layers "F.Cu" "F.Mask" "F.Paste")
			(net "PWM_OUT_FAN5_NET")
			(options
				(clearance outline)
				(anchor circle)
			)
			(primitives
				(gr_poly
					(pts
						(arc
							(start -0.1778 -0.2794)
							(mid -0.249642 -0.249642)
							(end -0.2794 -0.1778)
						)
						(arc
							(start -0.2794 0.1778)
							(mid -0.249642 0.249642)
							(end -0.1778 0.2794)
						)
						(arc
							(start 0.1778 0.2794)
							(mid 0.249642 0.249642)
							(end 0.2794 0.1778)
						)
						(arc
							(start 0.2794 -0.1778)
							(mid 0.249642 -0.249642)
							(end 0.1778 -0.2794)
						)
					)
					(width 0)
					(fill yes)
				)
			)
		)
		(pad "2" smd custom
			(at 0 0.4445 180)
			(size 0.1397 0.1397)
			(layers "F.Cu" "F.Mask" "F.Paste")
			(net "PWM_OUT_FAN5")
			(options
				(clearance outline)
				(anchor circle)
			)
			(primitives
				(gr_poly
					(pts
						(arc
							(start -0.1778 -0.2794)
							(mid -0.249642 -0.249642)
							(end -0.2794 -0.1778)
						)
						(arc
							(start -0.2794 0.1778)
							(mid -0.249642 0.249642)
							(end -0.1778 0.2794)
						)
						(arc
							(start 0.1778 0.2794)
							(mid 0.249642 0.249642)
							(end 0.2794 0.1778)
						)
						(arc
							(start 0.2794 -0.1778)
							(mid 0.249642 -0.249642)
							(end 0.1778 -0.2794)
						)
					)
					(width 0)
					(fill yes)
				)
			)
		)
	)
)
